FILE_TYPE = CONNECTIVITY;
{Allegro Design Entry HDL 17.2-2016 S081 (4005846) 1/11/2022}
"PAGE_NUMBER" = 148;
0"NC";
1"GND\g";
2"GND\g";
3"GND\g";
4"P3V3_STBY\g";
5"GND\g";
6"GND\g";
7"P3V3_STBY\g";
8"GND\g";
9"P3V3_STBY\g";
10"GND\g";
11"GND\g";
12"GND\g";
13"SCM_JTAG_MUX_S0";
14"SCM_JTAG_MUX_S1";
15"U212_EN_N";
16"GND\g";
17"JTAG_SCM_TDI";
18"JTAG_SCM_TDO";
19"P3V3_STBY\g";
20"U160_EN_N";
21"JTAG_SCM_TMS";
22"GND\g";
23"P3V3_STBY\g";
24"HPM_FW_RECOVERY_R";
25"JTAG_SCM_TCK";
26"P3V3_STBY\g";
27"JTAG_SCM_MUX_R_TDO";
28"JTAG_SCM_MUX_R_TCK";
29"TP_JTAG_SCM_SLOT3_R_TCK";
30"JTAG_SCM_MUX_R_TMS";
31"TP_JTAG_SCM_SLOT3_R_TDO";
32"JTAG_SCM_MUX_R_TDI";
33"TP_JTAG_SCM_SLOT3_R_TMS";
34"TP_JTAG_SCM_SLOT3_R_TDI";
35"JTAG_SCM_PLD_R_TDO";
36"JTAG_SCM_PLD_R_TDI";
37"JTAG_SCM_PLD_R_TMS";
38"JTAG_SCM_MUX_TDO";
39"JTAG_SCM_PLD_TDO";
40"JTAG_SCM_MUX_TDI";
41"JTAG_SCM_PLD_TDI";
42"JTAG_SCM_MUX_TMS";
43"JTAG_SCM_PLD_TMS";
44"JTAG_SCM_PLD_R_TCK";
45"JTAG_SCM_TDO";
46"JTAG_SCM_TMS";
47"JTAG_SCM_TDI";
48"JTAG_SCM_TCK";
49"P3V3_STBY\g";
50"JTAG_SCM_MUX_TCK";
51"JTAG_SCM_PLD_TCK";
52"JTAG_SCM_MUX_TDI";
53"JTAG_SCM_MUX_TDO";
54"JTAG_SCM_MUX_TMS";
55"JTAG_SCM_MUX_TCK";
56"P3V3_STBY\g";
57"GND\g";
58"GND\g";
%"Q_RES"
"2","(-2875,6050)","0","pure_quanta","I244";
;
LOCATION"R1734"
$SEC"1"
CDS_SEC"1"
WATTAGE"1/16W"
MATERIAL"CHIP"
TOLERANCE"1%"
VALUE"10K"
PART_NUMBER"CS31002FB08"
PACK_TYPE"0402LF"
CDS_LIB"pure_quanta";
"A"
$PN"1"49;
"B"
$PN"2"48;
%"Q_RES"
"2","(-3125,6050)","0","pure_quanta","I245";
;
LOCATION"R1731"
$SEC"1"
CDS_SEC"1"
WATTAGE"1/16W"
MATERIAL"CHIP"
TOLERANCE"1%"
VALUE"10K"
PACK_TYPE"0402LF"
CDS_LIB"pure_quanta"
PART_NUMBER"CS31002FB08";
"A"
$PN"1"49;
"B"
$PN"2"46;
%"Q_RES"
"2","(-2875,5550)","0","pure_quanta","I246";
;
LOCATION"R1735"
$SEC"1"
CDS_SEC"1"
MATERIAL"EMPTY"
TOLERANCE"1%"
VALUE"10K"
CDS_LIB"pure_quanta"
WATTAGE"1/16W"
PART_NUMBER"CS31002FB08"
PACK_TYPE"0402LF";
"A"
$PN"1"48;
"B"
$PN"2"1;
%"UNIVERSAL_GND"
"1","(-2875,5325)","0","pure_quanta_power","I247";
;
CDS_LIB"pure_quanta_power"
HDL_POWER"GND";
"A"1;
%"UNIVERSAL_POWER"
"1","(-3525,6400)","0","pure_quanta_power","I248";
;
HDL_POWER"P3V3_STBY"
CDS_LIB"pure_quanta_power";
"A"49;
%"Q_RES"
"2","(-3325,6050)","0","pure_quanta","I249";
;
LOCATION"R1728"
$SEC"1"
CDS_SEC"1"
TOLERANCE"1%"
VALUE"10K"
CDS_LIB"pure_quanta"
WATTAGE"1/16W"
MATERIAL"CHIP"
PART_NUMBER"CS31002FB08"
PACK_TYPE"0402LF";
"A"
$PN"1"49;
"B"
$PN"2"47;
%"Q_RES"
"2","(-3525,6050)","0","pure_quanta","I250";
;
LOCATION"R1727"
$SEC"1"
CDS_SEC"1"
TOLERANCE"1%"
VALUE"10K"
CDS_LIB"pure_quanta"
WATTAGE"1/16W"
MATERIAL"CHIP"
PART_NUMBER"CS31002FB08"
PACK_TYPE"0402LF";
"A"
$PN"1"49;
"B"
$PN"2"45;
%"Q_RES"
"2","(-450,6025)","0","pure_quanta","I255";
;
LOCATION"R1747"
$SEC"1"
CDS_SEC"1"
WATTAGE"1/16W"
MATERIAL"CHIP"
TOLERANCE"1%"
VALUE"10K"
PART_NUMBER"CS31002FB08"
PACK_TYPE"0402LF"
CDS_LIB"pure_quanta";
"A"
$PN"1"56;
"B"
$PN"2"55;
%"Q_RES"
"2","(-675,6025)","0","pure_quanta","I256";
;
LOCATION"R1746"
$SEC"1"
CDS_SEC"1"
WATTAGE"1/16W"
MATERIAL"CHIP"
TOLERANCE"1%"
VALUE"10K"
PACK_TYPE"0402LF"
CDS_LIB"pure_quanta"
PART_NUMBER"CS31002FB08";
"A"
$PN"1"56;
"B"
$PN"2"54;
%"Q_RES"
"2","(-875,6025)","0","pure_quanta","I257";
;
LOCATION"R1745"
$SEC"1"
CDS_SEC"1"
TOLERANCE"1%"
VALUE"10K"
CDS_LIB"pure_quanta"
WATTAGE"1/16W"
MATERIAL"CHIP"
PART_NUMBER"CS31002FB08"
PACK_TYPE"0402LF";
"A"
$PN"1"56;
"B"
$PN"2"53;
%"Q_RES"
"2","(-450,5525)","0","pure_quanta","I258";
;
LOCATION"R1748"
$SEC"1"
CDS_SEC"1"
MATERIAL"EMPTY"
TOLERANCE"1%"
VALUE"10K"
CDS_LIB"pure_quanta"
WATTAGE"1/16W"
PART_NUMBER"CS31002FB08"
PACK_TYPE"0402LF";
"A"
$PN"1"55;
"B"
$PN"2"2;
%"UNIVERSAL_GND"
"1","(-450,5300)","0","pure_quanta_power","I259";
;
CDS_LIB"pure_quanta_power"
HDL_POWER"GND";
"A"2;
%"UNIVERSAL_POWER"
"1","(-1075,6375)","0","pure_quanta_power","I260";
;
HDL_POWER"P3V3_STBY"
CDS_LIB"pure_quanta_power";
"A"56;
%"Q_RES"
"2","(-1075,6025)","0","pure_quanta","I261";
;
LOCATION"R1744"
$SEC"1"
CDS_SEC"1"
TOLERANCE"1%"
VALUE"10K"
CDS_LIB"pure_quanta"
WATTAGE"1/16W"
MATERIAL"CHIP"
PART_NUMBER"CS31002FB08"
PACK_TYPE"0402LF";
"A"
$PN"1"56;
"B"
$PN"2"52;
%"74HC4052PW"
"1","(-4875,4050)","0","pure_quanta","I266";
;
LOCATION"U160"
$SEC"1"
CDS_SEC"1"
PART_TYPE"SMLF"
MATERIAL"IC"
VALUE"74HC4052PW"
PART_NUMBER"ALHC4052K07"
CDS_LMAN_SYM_OUTLINE"-175,325,175,-325"
NEEDS_NO_SIZE"TRUE"
CDS_LIB"pure_quanta";
"VCC"
$PN"16"26;
"1Y2"
$PN"15"44;
"1Y1"
$PN"14"28;
"1Z"
$PN"13"25;
"1Y0"
$PN"12"29;
"1Y3"
$PN"11"44;
"S0"
$PN"10"13;
"S1"
$PN"9"14;
"GND"
$PN"8"22;
"VEE"
$PN"7"22;
"E_N \B"
$PN"6"20;
"2Y1"
$PN"5"30;
"2Y3"
$PN"4"37;
"2Z"
$PN"3"21;
"2Y2"
$PN"2"37;
"2Y0"
$PN"1"33;
%"UNIVERSAL_GND"
"1","(-4475,3525)","0","pure_quanta_power","I267";
;
CDS_LIB"pure_quanta_power"
HDL_POWER"GND";
"A"22;
%"UNIVERSAL_POWER"
"1","(-5350,4875)","0","pure_quanta_power","I292";
;
HDL_POWER"P3V3_STBY"
CDS_LIB"pure_quanta_power";
"A"26;
%"Q_CAP"
"1","(-5475,4575)","0","pure_quanta","I293";
;
LOCATION"C1554"
$SEC"1"
CDS_SEC"1"
MATERIAL"X7R"
TOLERANCE"10%"
VALUE"0.1UF"
PART_NUMBER"CH4103K1B08"
VOLTAGE"16V"
PACK_TYPE"C0402"
CDS_LIB"pure_quanta";
"B"
$PN"2"3;
"A"
$PN"1"26;
%"UNIVERSAL_GND"
"1","(-5475,4375)","0","pure_quanta_power","I294";
;
CDS_LIB"pure_quanta_power"
HDL_POWER"GND";
"A"3;
%"UNIVERSAL_POWER"
"1","(-7700,4375)","0","pure_quanta_power","I295";
;
HDL_POWER"P3V3_STBY"
CDS_LIB"pure_quanta_power";
"A"4;
%"UNIVERSAL_POWER"
"1","(-5350,2925)","0","pure_quanta_power","I298";
;
HDL_POWER"P3V3_STBY"
CDS_LIB"pure_quanta_power";
"A"19;
%"Q_CAP"
"1","(-5475,2625)","0","pure_quanta","I299";
;
LOCATION"C194"
$SEC"1"
CDS_SEC"1"
MATERIAL"X7R"
TOLERANCE"10%"
VALUE"0.1UF"
PART_NUMBER"CH4103K1B08"
VOLTAGE"16V"
PACK_TYPE"C0402"
CDS_LIB"pure_quanta";
"B"
$PN"2"5;
"A"
$PN"1"19;
%"UNIVERSAL_GND"
"1","(-5475,2425)","0","pure_quanta_power","I300";
;
CDS_LIB"pure_quanta_power"
HDL_POWER"GND";
"A"5;
%"UNIVERSAL_GND"
"1","(-4425,1600)","0","pure_quanta_power","I301";
;
CDS_LIB"pure_quanta_power"
HDL_POWER"GND";
"A"16;
%"74HC4052PW"
"1","(-4825,2100)","0","pure_quanta","I302";
;
LOCATION"U212"
$SEC"1"
CDS_SEC"1"
PART_TYPE"SMLF"
MATERIAL"IC"
VALUE"74HC4052PW"
PART_NUMBER"ALHC4052K07"
CDS_LMAN_SYM_OUTLINE"-175,325,175,-325"
NEEDS_NO_SIZE"TRUE"
CDS_LIB"pure_quanta";
"VCC"
$PN"16"19;
"1Y2"
$PN"15"36;
"1Y1"
$PN"14"32;
"1Z"
$PN"13"17;
"1Y0"
$PN"12"34;
"1Y3"
$PN"11"36;
"S0"
$PN"10"13;
"S1"
$PN"9"14;
"GND"
$PN"8"16;
"VEE"
$PN"7"16;
"E_N \B"
$PN"6"15;
"2Y1"
$PN"5"27;
"2Y3"
$PN"4"35;
"2Z"
$PN"3"18;
"2Y2"
$PN"2"35;
"2Y0"
$PN"1"31;
%"Q_RES"
"2","(-7700,4150)","0","pure_quanta","I305";
;
LOCATION"R1730"
$SEC"1"
CDS_SEC"1"
WATTAGE"1/16W"
MATERIAL"EMPTY"
TOLERANCE"5%"
VALUE"4.7K"
PART_NUMBER"TMP_QCS24702JB38"
PACK_TYPE"0402LF"
CDS_LIB"pure_quanta";
"A"
$PN"1"4;
"B"
$PN"2"14;
%"Q_RES"
"2","(-7750,3650)","0","pure_quanta","I306";
;
LOCATION"R1729"
$SEC"1"
CDS_SEC"1"
WATTAGE"1/16W"
MATERIAL"CHIP"
TOLERANCE"5%"
VALUE"4.7K"
PART_NUMBER"TMP_QCS24702JB38"
PACK_TYPE"0402LF"
CDS_LIB"pure_quanta";
"A"
$PN"1"14;
"B"
$PN"2"6;
%"UNIVERSAL_GND"
"1","(-7750,3400)","0","pure_quanta_power","I307";
;
CDS_LIB"pure_quanta_power"
HDL_POWER"GND";
"A"6;
%"UNIVERSAL_POWER"
"1","(-7700,2375)","0","pure_quanta_power","I308";
;
HDL_POWER"P3V3_STBY"
CDS_LIB"pure_quanta_power";
"A"7;
%"Q_RES"
"2","(-7700,2150)","0","pure_quanta","I309";
;
LOCATION"R1659"
$SEC"1"
CDS_SEC"1"
WATTAGE"1/16W"
MATERIAL"EMPTY"
TOLERANCE"5%"
VALUE"4.7K"
PART_NUMBER"TMP_QCS24702JB38"
PACK_TYPE"0402LF"
CDS_LIB"pure_quanta";
"A"
$PN"1"7;
"B"
$PN"2"13;
%"Q_RES"
"2","(-7750,1650)","0","pure_quanta","I310";
;
LOCATION"R1658"
$SEC"1"
CDS_SEC"1"
WATTAGE"1/16W"
MATERIAL"CHIP"
TOLERANCE"5%"
VALUE"4.7K"
PART_NUMBER"TMP_QCS24702JB38"
PACK_TYPE"0402LF"
CDS_LIB"pure_quanta";
"A"
$PN"1"13;
"B"
$PN"2"8;
%"UNIVERSAL_GND"
"1","(-7750,1400)","0","pure_quanta_power","I311";
;
CDS_LIB"pure_quanta_power"
HDL_POWER"GND";
"A"8;
%"Q_RES"
"1","(-3200,2025)","0","pure_quanta","I329";
;
LOCATION"R1739"
$SEC"1"
CDS_SEC"1"
MATERIAL"CHIP"
TOLERANCE"1%"
VALUE"22"
CDS_LIB"pure_quanta"
WATTAGE"1/16W"
PART_NUMBER"CS02202FB12"
PACK_TYPE"0402LF";
"B"
$PN"2"38;
"A"
$PN"1"27;
%"Q_RES"
"1","(-3200,2075)","0","pure_quanta","I332";
;
LOCATION"R1743"
$SEC"1"
CDS_SEC"1"
MATERIAL"CHIP"
TOLERANCE"1%"
VALUE"22"
CDS_LIB"pure_quanta"
WATTAGE"1/16W"
PART_NUMBER"CS02202FB12"
PACK_TYPE"0402LF";
"B"
$PN"2"39;
"A"
$PN"1"35;
%"UNIVERSAL_POWER"
"1","(-6575,5775)","0","pure_quanta_power","I337";
;
HDL_POWER"P3V3_STBY"
CDS_LIB"pure_quanta_power"
BOM_COST"OCP3.0 ";
"A"9;
%"Q_RES"
"2","(-6575,5500)","0","pure_quanta","I339";
;
LOCATION"R1343"
$SEC"1"
CDS_SEC"1"
WATTAGE"1/16W"
MATERIAL"EMPTY"
TOLERANCE"5%"
VALUE"4.7K"
PART_NUMBER"TMP_QCS24702JB38"
PACK_TYPE"0402LF"
BOM_COST"OCP3.0 "
CDS_LIB"pure_quanta";
"A"
$PN"1"9;
"B"
$PN"2"14;
%"SN74LVC1G07DBVR"
"1","(-7400,5225)","0","pure_quanta","I340";
;
LOCATION"U99"
$SEC"1"
CDS_SEC"1"
MATERIAL"EMPTY"
VALUE"SN74LVC1G07DBVR"
PART_NUMBER"AL1G0007024"
PACK_TYPE"SMLF"
NEEDS_NO_SIZE"TRUE"
CDS_LIB"pure_quanta";
"NC"
$PN"1"0;
"Y"
$PN"4"14;
"GND"
$PN"3"11;
"A"
$PN"2"24;
"VCC"
$PN"5"23;
%"UNIVERSAL_POWER"
"1","(-8000,5850)","0","pure_quanta_power","I341";
;
HDL_POWER"P3V3_STBY"
CDS_LIB"pure_quanta_power"
BOM_COST"OCP3.0 ";
"A"23;
%"Q_CAP"
"1","(-8000,5550)","0","pure_quanta","I342";
;
LOCATION"C553"
$SEC"1"
CDS_SEC"1"
MATERIAL"X7R"
TOLERANCE"10%"
VALUE"0.1UF"
PART_NUMBER"CH4104K1B00"
VOLTAGE"25V"
PACK_TYPE"0402"
BOM_COST"OCP3.0 "
CDS_LIB"pure_quanta";
"B"
$PN"2"10;
"A"
$PN"1"23;
%"UNIVERSAL_GND"
"1","(-8000,5350)","0","pure_quanta_power","I343";
;
CDS_LIB"pure_quanta_power"
BOM_COST"OCP3.0 "
HDL_POWER"GND";
"A"10;
%"UNIVERSAL_GND"
"1","(-7650,4950)","0","pure_quanta_power","I344";
;
CDS_LIB"pure_quanta_power"
HDL_POWER"GND";
"A"11;
%"Q_RES"
"1","(-3200,2275)","0","pure_quanta","I349";
;
LOCATION"R1738"
$SEC"1"
CDS_SEC"1"
MATERIAL"CHIP"
TOLERANCE"1%"
VALUE"22"
CDS_LIB"pure_quanta"
WATTAGE"1/16W"
PART_NUMBER"CS02202FB12"
PACK_TYPE"0402LF";
"B"
$PN"2"40;
"A"
$PN"1"32;
%"Q_RES"
"1","(-3200,2325)","0","pure_quanta","I352";
;
LOCATION"R1742"
$SEC"1"
CDS_SEC"1"
MATERIAL"CHIP"
TOLERANCE"1%"
VALUE"22"
CDS_LIB"pure_quanta"
WATTAGE"1/16W"
PART_NUMBER"CS02202FB12"
PACK_TYPE"0402LF";
"B"
$PN"2"41;
"A"
$PN"1"36;
%"Q_RES"
"1","(-3200,3975)","0","pure_quanta","I357";
;
LOCATION"R1737"
$SEC"1"
CDS_SEC"1"
MATERIAL"CHIP"
TOLERANCE"1%"
VALUE"22"
CDS_LIB"pure_quanta"
WATTAGE"1/16W"
PART_NUMBER"CS02202FB12"
PACK_TYPE"0402LF";
"B"
$PN"2"42;
"A"
$PN"1"30;
%"Q_RES"
"1","(-3200,4225)","0","pure_quanta","I363";
;
LOCATION"R1736"
$SEC"1"
CDS_SEC"1"
MATERIAL"CHIP"
TOLERANCE"1%"
VALUE"22"
CDS_LIB"pure_quanta"
WATTAGE"1/16W"
PART_NUMBER"CS02202FB12"
PACK_TYPE"0402LF";
"B"
$PN"2"50;
"A"
$PN"1"28;
%"Q_RES"
"1","(-3200,4025)","0","pure_quanta","I366";
;
LOCATION"R1741"
$SEC"1"
CDS_SEC"1"
MATERIAL"CHIP"
TOLERANCE"1%"
VALUE"22"
CDS_LIB"pure_quanta"
WATTAGE"1/16W"
PART_NUMBER"CS02202FB12"
PACK_TYPE"0402LF";
"B"
$PN"2"43;
"A"
$PN"1"37;
%"Q_RES"
"1","(-3200,4275)","0","pure_quanta","I368";
;
LOCATION"R1740"
$SEC"1"
CDS_SEC"1"
MATERIAL"CHIP"
TOLERANCE"1%"
VALUE"22"
CDS_LIB"pure_quanta"
WATTAGE"1/16W"
PART_NUMBER"CS02202FB12"
PACK_TYPE"0402LF";
"B"
$PN"2"51;
"A"
$PN"1"44;
%"Q_RES"
"2","(-8025,5025)","0","pure_quanta","I369";
;
LOCATION"R1342"
$SEC"1"
CDS_SEC"1"
WATTAGE"1/16W"
MATERIAL"CHIP"
TOLERANCE"1%"
VALUE"10K"
PART_NUMBER"CS31002FB08"
PACK_TYPE"0402LF"
CDS_LIB"pure_quanta";
"A"
$PN"1"24;
"B"
$PN"2"12;
%"UNIVERSAL_GND"
"1","(-8025,4750)","0","pure_quanta_power","I370";
;
CDS_LIB"pure_quanta_power"
HDL_POWER"GND";
"A"12;
%"Q_RES"
"2","(-5725,3550)","0","pure_quanta","I371";
;
LOCATION"R1313"
$SEC"1"
CDS_SEC"1"
WATTAGE"1/16W"
MATERIAL"CHIP"
TOLERANCE"5%"
VALUE"4.7K"
PART_NUMBER"TMP_QCS24702JB38"
PACK_TYPE"0402LF"
CDS_LIB"pure_quanta";
"A"
$PN"1"20;
"B"
$PN"2"58;
%"UNIVERSAL_GND"
"1","(-5725,3400)","0","pure_quanta_power","I372";
;
CDS_LIB"pure_quanta_power"
HDL_POWER"GND";
"A"58;
%"Q_RES"
"2","(-5675,1600)","0","pure_quanta","I373";
;
LOCATION"R1318"
$SEC"1"
CDS_SEC"1"
WATTAGE"1/16W"
MATERIAL"CHIP"
TOLERANCE"5%"
VALUE"4.7K"
PART_NUMBER"TMP_QCS24702JB38"
PACK_TYPE"0402LF"
CDS_LIB"pure_quanta";
"A"
$PN"1"15;
"B"
$PN"2"57;
%"UNIVERSAL_GND"
"1","(-5675,1450)","0","pure_quanta_power","I374";
;
CDS_LIB"pure_quanta_power"
HDL_POWER"GND";
"A"57;
END.
